(kicad_pcb
	(version 20260206)
	(generator "pcbnew")
	(generator_version "10.0")
	(general
		(thickness 1.6)
		(legacy_teardrops no)
	)
	(paper "A4")
	(title_block
		(title "Wiwynn_Tioga_Pass_MB.brd")
		(comment 1 "Tioga Pass / footprints 526-533 of 4770")
	)
	(layers
		(0 "F.Cu" signal "TOP")
		(4 "In1.Cu" signal "L2GND")
		(6 "In2.Cu" signal "L3")
		(8 "In3.Cu" signal "L4GND")
		(10 "In4.Cu" signal "L5")
		(12 "In5.Cu" signal "L6GND")
		(14 "In6.Cu" signal "L7VCC")
		(16 "In7.Cu" signal "L8VCC")
		(18 "In8.Cu" signal "L9GND")
		(20 "In9.Cu" signal "L10")
		(22 "In10.Cu" signal "L11GND")
		(24 "In11.Cu" signal "L12")
		(26 "In12.Cu" signal "L13GND")
		(2 "B.Cu" signal "BOTTOM")
		(9 "F.Adhes" user "F.Adhesive")
		(11 "B.Adhes" user "B.Adhesive")
		(13 "F.Paste" user "Package Geometry/Pastemask Top")
		(15 "B.Paste" user "Package Geometry/Pastemask Bottom")
		(5 "F.SilkS" user "Ref Des/Silkscreen Top")
		(7 "B.SilkS" user "Ref Des/Silkscreen Bottom")
		(1 "F.Mask" user "Board Geometry/Soldermask Top")
		(3 "B.Mask" user "Board Geometry/Soldermask Bottom")
		(17 "Dwgs.User" user "User.Drawings")
		(19 "Cmts.User" user "User.Comments")
		(21 "Eco1.User" user "User.Eco1")
		(23 "Eco2.User" user "User.Eco2")
		(25 "Edge.Cuts" user "Board Geometry/Outline")
		(27 "Margin" user)
		(31 "F.CrtYd" user "Package Geometry/Place Bound Top")
		(29 "B.CrtYd" user "Package Geometry/Place Bound Bottom")
		(35 "F.Fab" user "Ref Des/Assembly Top")
		(33 "B.Fab" user "Ref Des/Assembly Bottom")
	)
	(footprint ""
		(layer "F.Cu")
		(at 340.614 -137.1727 90)
		(property "Reference" "C7A34"
			(at 0 0 90)
			(layer "F.SilkS")
			(hide yes)
			(effects
				(font
					(size 1.27 1.27)
				)
			)
		)
		(property "Value" ""
			(at 0 0 90)
			(layer "F.Fab")
			(effects
				(font
					(size 1.27 1.27)
				)
			)
		)
		(duplicate_pad_numbers_are_jumpers no)
		(fp_poly
			(pts
				(xy 0.3048 -0.1016) (xy 0.3048 0.9906) (xy -0.3048 0.9906) (xy -0.3048 -0.1016)
			)
			(stroke
				(width 0)
				(type default)
			)
			(fill no)
			(layer "F.CrtYd")
		)
		(fp_line
			(start 0.3048 -0.1016)
			(end -0.3048 -0.1016)
			(stroke
				(width 0.1)
				(type default)
			)
			(layer "F.Fab")
		)
		(fp_line
			(start -0.3048 -0.1016)
			(end -0.3048 0.9906)
			(stroke
				(width 0.1)
				(type default)
			)
			(layer "F.Fab")
		)
		(fp_line
			(start 0.3048 0.9906)
			(end 0.3048 -0.1016)
			(stroke
				(width 0.1)
				(type default)
			)
			(layer "F.Fab")
		)
		(fp_line
			(start -0.3048 0.9906)
			(end 0.3048 0.9906)
			(stroke
				(width 0.1)
				(type default)
			)
			(layer "F.Fab")
		)
		(pad "1" smd rect
			(at 0 0 90)
			(size 0.508 0.508)
			(layers "F.Cu" "F.Mask" "F.Paste")
			(net "VR_PVPP_DEF_PHASE")
		)
		(pad "2" smd rect
			(at 0 0.889 90)
			(size 0.508 0.508)
			(layers "F.Cu" "F.Mask" "F.Paste")
			(net "VR_PVPP_DEF_SNUB")
		)
		(zone
			(layer "F.Cu")
			(hatch none 0.5)
			(connect_pads
				(clearance 0)
			)
			(min_thickness 0.25)
			(keepout
				(tracks allowed)
				(vias not_allowed)
				(pads allowed)
				(copperpour not_allowed)
				(footprints allowed)
			)
			(placement
				(enabled no)
				(sheetname "")
			)
			(fill
				(thermal_gap 0.5)
				(thermal_bridge_width 0.5)
				(island_removal_mode 0)
			)
			(polygon
				(pts
					(xy 340.868 -136.9187) (xy 340.868 -137.4267) (xy 341.249 -137.4267) (xy 341.249 -136.9187)
				)
			)
		)
		(zone
			(layer "F.Cu")
			(hatch none 0.5)
			(connect_pads
				(clearance 0)
			)
			(min_thickness 0.25)
			(keepout
				(tracks not_allowed)
				(vias allowed)
				(pads allowed)
				(copperpour not_allowed)
				(footprints allowed)
			)
			(placement
				(enabled no)
				(sheetname "")
			)
			(fill
				(thermal_gap 0.5)
				(thermal_bridge_width 0.5)
				(island_removal_mode 0)
			)
			(polygon
				(pts
					(xy 341.249 -136.9187) (xy 341.249 -137.4267) (xy 340.868 -137.4267) (xy 340.868 -136.9187)
				)
			)
		)
	)
	(footprint ""
		(layer "F.Cu")
		(at 29.6164 -67.757802 -90)
		(property "Reference" "C1D35"
			(at 0 0 270)
			(layer "F.SilkS")
			(hide yes)
			(effects
				(font
					(size 1.27 1.27)
				)
			)
		)
		(property "Value" ""
			(at 0 0 270)
			(layer "F.Fab")
			(effects
				(font
					(size 1.27 1.27)
				)
			)
		)
		(duplicate_pad_numbers_are_jumpers no)
		(fp_rect
			(start 0.3048 -0.1016)
			(end -0.3048 0.9906)
			(stroke
				(width 0)
				(type default)
			)
			(fill no)
			(layer "F.CrtYd")
		)
		(fp_line
			(start -0.3048 0.9906)
			(end 0.3048 0.9906)
			(stroke
				(width 0.1)
				(type default)
			)
			(layer "F.Fab")
		)
		(fp_line
			(start 0.3048 0.9906)
			(end 0.3048 -0.1016)
			(stroke
				(width 0.1)
				(type default)
			)
			(layer "F.Fab")
		)
		(fp_line
			(start -0.3048 -0.1016)
			(end -0.3048 0.9906)
			(stroke
				(width 0.1)
				(type default)
			)
			(layer "F.Fab")
		)
		(fp_line
			(start 0.3048 -0.1016)
			(end -0.3048 -0.1016)
			(stroke
				(width 0.1)
				(type default)
			)
			(layer "F.Fab")
		)
		(pad "1" smd rect
			(at 0 0 270)
			(size 0.508 0.508)
			(layers "F.Cu" "F.Mask" "F.Paste")
			(net "VR_FET_SW_P12V_STBY_PVCCIN_CPU1")
		)
		(pad "2" smd rect
			(at 0 0.889 270)
			(size 0.508 0.508)
			(layers "F.Cu" "F.Mask" "F.Paste")
			(net "GND")
		)
		(zone
			(layer "F.Cu")
			(hatch none 0.5)
			(connect_pads
				(clearance 0)
			)
			(min_thickness 0.25)
			(keepout
				(tracks allowed)
				(vias not_allowed)
				(pads allowed)
				(copperpour not_allowed)
				(footprints allowed)
			)
			(placement
				(enabled no)
				(sheetname "")
			)
			(fill
				(thermal_gap 0.5)
				(thermal_bridge_width 0.5)
				(island_removal_mode 0)
			)
			(polygon
				(pts
					(xy 29.3624 -67.503802) (xy 29.3624 -68.011802) (xy 28.9814 -68.011802) (xy 28.9814 -67.503802)
				)
			)
		)
		(zone
			(layer "F.Cu")
			(hatch none 0.5)
			(connect_pads
				(clearance 0)
			)
			(min_thickness 0.25)
			(keepout
				(tracks not_allowed)
				(vias allowed)
				(pads allowed)
				(copperpour not_allowed)
				(footprints allowed)
			)
			(placement
				(enabled no)
				(sheetname "")
			)
			(fill
				(thermal_gap 0.5)
				(thermal_bridge_width 0.5)
				(island_removal_mode 0)
			)
			(polygon
				(pts
					(xy 29.3624 -67.503802) (xy 29.3624 -68.011802) (xy 28.9814 -68.011802) (xy 28.9814 -67.503802)
				)
			)
		)
	)
	(footprint ""
		(layer "F.Cu")
		(at 93.136212 -12.824968 -90)
		(property "Reference" "C2G8"
			(at 0 0 270)
			(layer "F.SilkS")
			(hide yes)
			(effects
				(font
					(size 1.27 1.27)
				)
			)
		)
		(property "Value" ""
			(at 0 0 270)
			(layer "F.Fab")
			(effects
				(font
					(size 1.27 1.27)
				)
			)
		)
		(duplicate_pad_numbers_are_jumpers no)
		(fp_rect
			(start -0.500126 1.598422)
			(end 0.500126 -0.201422)
			(stroke
				(width 0)
				(type default)
			)
			(fill no)
			(layer "F.CrtYd")
		)
		(fp_line
			(start -0.500126 1.598422)
			(end -0.500126 -0.201422)
			(stroke
				(width 0.1)
				(type default)
			)
			(layer "F.Fab")
		)
		(fp_line
			(start 0.500126 1.598422)
			(end -0.500126 1.598422)
			(stroke
				(width 0.1)
				(type default)
			)
			(layer "F.Fab")
		)
		(fp_line
			(start -0.500126 -0.201422)
			(end 0.500126 -0.201422)
			(stroke
				(width 0.1)
				(type default)
			)
			(layer "F.Fab")
		)
		(fp_line
			(start 0.500126 -0.201422)
			(end 0.500126 1.598422)
			(stroke
				(width 0.1)
				(type default)
			)
			(layer "F.Fab")
		)
		(pad "1" smd rect
			(at 0 0 180)
			(size 0.889 0.9906)
			(layers "F.Cu" "F.Mask" "F.Paste")
			(net "PVDDQ_GHJ")
		)
		(pad "2" smd rect
			(at 0 1.397 180)
			(size 0.889 0.9906)
			(layers "F.Cu" "F.Mask" "F.Paste")
			(net "GND")
		)
		(zone
			(layer "F.Cu")
			(hatch none 0.5)
			(connect_pads
				(clearance 0)
			)
			(min_thickness 0.25)
			(keepout
				(tracks allowed)
				(vias not_allowed)
				(pads allowed)
				(copperpour not_allowed)
				(footprints allowed)
			)
			(placement
				(enabled no)
				(sheetname "")
			)
			(fill
				(thermal_gap 0.5)
				(thermal_bridge_width 0.5)
				(island_removal_mode 0)
			)
			(polygon
				(pts
					(xy 92.183712 -13.320268) (xy 92.183712 -12.329668) (xy 92.691712 -12.329668) (xy 92.691712 -13.320268)
				)
			)
		)
		(zone
			(layer "F.Cu")
			(hatch none 0.5)
			(connect_pads
				(clearance 0)
			)
			(min_thickness 0.25)
			(keepout
				(tracks not_allowed)
				(vias allowed)
				(pads allowed)
				(copperpour not_allowed)
				(footprints allowed)
			)
			(placement
				(enabled no)
				(sheetname "")
			)
			(fill
				(thermal_gap 0.5)
				(thermal_bridge_width 0.5)
				(island_removal_mode 0)
			)
			(polygon
				(pts
					(xy 92.183712 -13.320268) (xy 92.183712 -12.329668) (xy 92.691712 -12.329668) (xy 92.691712 -13.320268)
				)
			)
		)
	)
	(footprint ""
		(layer "F.Cu")
		(at 214.503 -59.17692 180)
		(property "Reference" "C4E11"
			(at 0 0 180)
			(layer "F.SilkS")
			(hide yes)
			(effects
				(font
					(size 1.27 1.27)
				)
			)
		)
		(property "Value" ""
			(at 0 0 180)
			(layer "F.Fab")
			(effects
				(font
					(size 1.27 1.27)
				)
			)
		)
		(duplicate_pad_numbers_are_jumpers no)
		(fp_poly
			(pts
				(xy -0.4953 -0.2032) (xy 0.4953 -0.2032) (xy 0.4953 1.6002) (xy -0.4953 1.6002)
			)
			(stroke
				(width 0)
				(type default)
			)
			(fill no)
			(layer "F.CrtYd")
		)
		(fp_line
			(start 0.4953 1.6002)
			(end -0.4953 1.6002)
			(stroke
				(width 0.1)
				(type default)
			)
			(layer "F.Fab")
		)
		(fp_line
			(start 0.4953 -0.2032)
			(end 0.4953 1.6002)
			(stroke
				(width 0.1)
				(type default)
			)
			(layer "F.Fab")
		)
		(fp_line
			(start -0.4953 1.6002)
			(end -0.4953 -0.2032)
			(stroke
				(width 0.1)
				(type default)
			)
			(layer "F.Fab")
		)
		(fp_line
			(start -0.4953 -0.2032)
			(end 0.4953 -0.2032)
			(stroke
				(width 0.1)
				(type default)
			)
			(layer "F.Fab")
		)
		(pad "1" smd rect
			(at 0 0 180)
			(size 0.762 0.889)
			(layers "F.Cu" "F.Mask" "F.Paste")
			(net "PVCCIN_CPU0")
		)
		(pad "2" smd rect
			(at 0 1.397 180)
			(size 0.762 0.889)
			(layers "F.Cu" "F.Mask" "F.Paste")
			(net "GND")
		)
		(zone
			(layer "F.Cu")
			(hatch none 0.5)
			(connect_pads
				(clearance 0)
			)
			(min_thickness 0.25)
			(keepout
				(tracks not_allowed)
				(vias allowed)
				(pads allowed)
				(copperpour not_allowed)
				(footprints allowed)
			)
			(placement
				(enabled no)
				(sheetname "")
			)
			(fill
				(thermal_gap 0.5)
				(thermal_bridge_width 0.5)
				(island_removal_mode 0)
			)
			(polygon
				(pts
					(xy 214.884 -59.62142) (xy 214.122 -59.62142) (xy 214.122 -60.12942) (xy 214.884 -60.12942)
				)
			)
		)
	)
	(footprint ""
		(layer "F.Cu")
		(at 466.344 -137.033 90)
		(property "Reference" "U9A5"
			(at -0.51816 2.26949 90)
			(unlocked yes)
			(layer "F.SilkS")
			(effects
				(font
					(size 0.7874 0.5842)
					(thickness 0.1524)
				)
				(justify left)
			)
		)
		(property "Value" ""
			(at 0 0 90)
			(layer "F.Fab")
			(effects
				(font
					(size 1.27 1.27)
				)
			)
		)
		(duplicate_pad_numbers_are_jumpers no)
		(fp_circle
			(center -0.4699 -0.8382)
			(end -0.4699 -0.7112)
			(stroke
				(width 0.254)
				(type default)
			)
			(fill no)
			(layer "F.SilkS")
		)
		(fp_poly
			(pts
				(xy 0.21463 -0.450088) (xy 1.56337 -0.450088) (xy 1.56337 1.75006) (xy 0.21463 1.75006)
			)
			(stroke
				(width 0)
				(type default)
			)
			(fill no)
			(layer "F.CrtYd")
		)
		(fp_line
			(start 1.56337 -0.450088)
			(end 1.56337 1.75006)
			(stroke
				(width 0.1)
				(type default)
			)
			(layer "F.Fab")
		)
		(fp_line
			(start 0.21463 -0.450088)
			(end 1.56337 -0.450088)
			(stroke
				(width 0.1)
				(type default)
			)
			(layer "F.Fab")
		)
		(fp_line
			(start 1.56337 1.75006)
			(end 0.21463 1.75006)
			(stroke
				(width 0.1)
				(type default)
			)
			(layer "F.Fab")
		)
		(fp_line
			(start 0.21463 1.75006)
			(end 0.21463 -0.450088)
			(stroke
				(width 0.1)
				(type default)
			)
			(layer "F.Fab")
		)
		(fp_circle
			(center -0.4699 -0.8382)
			(end -0.4699 -0.7112)
			(stroke
				(width 0.254)
				(type default)
			)
			(fill no)
			(layer "F.Fab")
		)
		(pad "1" smd rect
			(at 0 0 90)
			(size 1.016 0.381)
			(layers "F.Cu" "F.Mask" "F.Paste")
			(net "FM_CPU0_OR_CPU1_MCP_PRES")
		)
		(pad "2" smd rect
			(at 0 0.649986 90)
			(size 1.016 0.381)
			(layers "F.Cu" "F.Mask" "F.Paste")
			(net "JTAG_MCP_TCK_R1")
		)
		(pad "3" smd rect
			(at 0 1.299972 90)
			(size 1.016 0.381)
			(layers "F.Cu" "F.Mask" "F.Paste")
			(net "GND")
		)
		(pad "4" smd rect
			(at 1.778 1.299972 90)
			(size 1.016 0.381)
			(layers "F.Cu" "F.Mask" "F.Paste")
			(net "GND")
		)
		(pad "5" smd rect
			(at 1.778 0 90)
			(size 1.016 0.381)
			(layers "F.Cu" "F.Mask" "F.Paste")
			(net "P3V3_STBY")
		)
	)
	(footprint ""
		(layer "F.Cu")
		(at 281.178 -74.041 90)
		(property "Reference" "R6D8"
			(at 0 0 90)
			(layer "F.SilkS")
			(hide yes)
			(effects
				(font
					(size 1.27 1.27)
				)
			)
		)
		(property "Value" ""
			(at 0 0 90)
			(layer "F.Fab")
			(effects
				(font
					(size 1.27 1.27)
				)
			)
		)
		(duplicate_pad_numbers_are_jumpers no)
		(fp_rect
			(start -0.2794 -0.1016)
			(end 0.2794 0.9906)
			(stroke
				(width 0)
				(type default)
			)
			(fill no)
			(layer "F.CrtYd")
		)
		(fp_line
			(start 0.2794 -0.1016)
			(end -0.2794 -0.1016)
			(stroke
				(width 0.1)
				(type default)
			)
			(layer "F.Fab")
		)
		(fp_line
			(start -0.2794 -0.1016)
			(end -0.2794 0.9906)
			(stroke
				(width 0.1)
				(type default)
			)
			(layer "F.Fab")
		)
		(fp_line
			(start 0.2794 0.9906)
			(end 0.2794 -0.1016)
			(stroke
				(width 0.1)
				(type default)
			)
			(layer "F.Fab")
		)
		(fp_line
			(start -0.2794 0.9906)
			(end 0.2794 0.9906)
			(stroke
				(width 0.1)
				(type default)
			)
			(layer "F.Fab")
		)
		(pad "1" smd rect
			(at 0 0 90)
			(size 0.508 0.508)
			(layers "F.Cu" "F.Mask" "F.Paste")
			(net "PVCCIO_CPU0")
		)
		(pad "2" smd rect
			(at 0 0.889 90)
			(size 0.508 0.508)
			(layers "F.Cu" "F.Mask" "F.Paste")
			(net "PWRGD_CPU0_G")
		)
		(zone
			(layer "F.Cu")
			(hatch none 0.5)
			(connect_pads
				(clearance 0)
			)
			(min_thickness 0.25)
			(keepout
				(tracks allowed)
				(vias not_allowed)
				(pads allowed)
				(copperpour not_allowed)
				(footprints allowed)
			)
			(placement
				(enabled no)
				(sheetname "")
			)
			(fill
				(thermal_gap 0.5)
				(thermal_bridge_width 0.5)
				(island_removal_mode 0)
			)
			(polygon
				(pts
					(xy 281.432 -73.787) (xy 281.813 -73.787) (xy 281.813 -74.295) (xy 281.432 -74.295)
				)
			)
		)
		(zone
			(layer "F.Cu")
			(hatch none 0.5)
			(connect_pads
				(clearance 0)
			)
			(min_thickness 0.25)
			(keepout
				(tracks not_allowed)
				(vias allowed)
				(pads allowed)
				(copperpour not_allowed)
				(footprints allowed)
			)
			(placement
				(enabled no)
				(sheetname "")
			)
			(fill
				(thermal_gap 0.5)
				(thermal_bridge_width 0.5)
				(island_removal_mode 0)
			)
			(polygon
				(pts
					(xy 281.432 -73.787) (xy 281.813 -73.787) (xy 281.813 -74.295) (xy 281.432 -74.295)
				)
			)
		)
	)
	(footprint ""
		(layer "F.Cu")
		(at 338.235036 -25.265126 90)
		(property "Reference" "C7F4"
			(at 0 0 90)
			(layer "F.SilkS")
			(hide yes)
			(effects
				(font
					(size 1.27 1.27)
				)
			)
		)
		(property "Value" ""
			(at 0 0 90)
			(layer "F.Fab")
			(effects
				(font
					(size 1.27 1.27)
				)
			)
		)
		(duplicate_pad_numbers_are_jumpers no)
		(fp_rect
			(start 0.4953 1.6002)
			(end -0.4953 -0.2032)
			(stroke
				(width 0)
				(type default)
			)
			(fill no)
			(layer "F.CrtYd")
		)
		(fp_line
			(start 0.4953 -0.2032)
			(end 0.4953 1.6002)
			(stroke
				(width 0.1)
				(type default)
			)
			(layer "F.Fab")
		)
		(fp_line
			(start -0.4953 -0.2032)
			(end 0.4953 -0.2032)
			(stroke
				(width 0.1)
				(type default)
			)
			(layer "F.Fab")
		)
		(fp_line
			(start 0.4953 1.6002)
			(end -0.4953 1.6002)
			(stroke
				(width 0.1)
				(type default)
			)
			(layer "F.Fab")
		)
		(fp_line
			(start -0.4953 1.6002)
			(end -0.4953 -0.2032)
			(stroke
				(width 0.1)
				(type default)
			)
			(layer "F.Fab")
		)
		(pad "1" smd rect
			(at 0 0 90)
			(size 0.762 0.889)
			(layers "F.Cu" "F.Mask" "F.Paste")
			(net "VR_PVPP_ABC_PHASE")
		)
		(pad "2" smd rect
			(at 0 1.397 90)
			(size 0.762 0.889)
			(layers "F.Cu" "F.Mask" "F.Paste")
			(net "VR_PVPP_ABC_BOOT_R")
		)
		(zone
			(layer "F.Cu")
			(hatch none 0.5)
			(connect_pads
				(clearance 0)
			)
			(min_thickness 0.25)
			(keepout
				(tracks not_allowed)
				(vias allowed)
				(pads allowed)
				(copperpour not_allowed)
				(footprints allowed)
			)
			(placement
				(enabled no)
				(sheetname "")
			)
			(fill
				(thermal_gap 0.5)
				(thermal_bridge_width 0.5)
				(island_removal_mode 0)
			)
			(polygon
				(pts
					(xy 339.187536 -25.646126) (xy 338.679536 -25.646126) (xy 338.679536 -24.884126) (xy 339.187536 -24.884126)
				)
			)
		)
	)
	(footprint ""
		(layer "F.Cu")
		(at 377.567444 -10.916158)
		(property "Reference" "C7G18"
			(at 0 0 0)
			(layer "F.SilkS")
			(hide yes)
			(effects
				(font
					(size 1.27 1.27)
				)
			)
		)
		(property "Value" ""
			(at 0 0 0)
			(layer "F.Fab")
			(effects
				(font
					(size 1.27 1.27)
				)
			)
		)
		(duplicate_pad_numbers_are_jumpers no)
		(fp_rect
			(start -0.3048 0.9906)
			(end 0.3048 -0.1016)
			(stroke
				(width 0)
				(type default)
			)
			(fill no)
			(layer "F.CrtYd")
		)
		(fp_line
			(start -0.3048 -0.1016)
			(end -0.3048 0.9906)
			(stroke
				(width 0.1)
				(type default)
			)
			(layer "F.Fab")
		)
		(fp_line
			(start -0.3048 0.9906)
			(end 0.3048 0.9906)
			(stroke
				(width 0.1)
				(type default)
			)
			(layer "F.Fab")
		)
		(fp_line
			(start 0.3048 -0.1016)
			(end -0.3048 -0.1016)
			(stroke
				(width 0.1)
				(type default)
			)
			(layer "F.Fab")
		)
		(fp_line
			(start 0.3048 0.9906)
			(end 0.3048 -0.1016)
			(stroke
				(width 0.1)
				(type default)
			)
			(layer "F.Fab")
		)
		(pad "1" smd rect
			(at 0 0)
			(size 0.508 0.508)
			(layers "F.Cu" "F.Mask" "F.Paste")
			(net "P3E_CPU0_PE2_SS_TXN<9>")
		)
		(pad "2" smd rect
			(at 0 0.889)
			(size 0.508 0.508)
			(layers "F.Cu" "F.Mask" "F.Paste")
			(net "P3E_CPU0_PE2_SS_C_TXN<9>")
		)
		(zone
			(layer "F.Cu")
			(hatch none 0.5)
			(connect_pads
				(clearance 0)
			)
			(min_thickness 0.25)
			(keepout
				(tracks allowed)
				(vias not_allowed)
				(pads allowed)
				(copperpour not_allowed)
				(footprints allowed)
			)
			(placement
				(enabled no)
				(sheetname "")
			)
			(fill
				(thermal_gap 0.5)
				(thermal_bridge_width 0.5)
				(island_removal_mode 0)
			)
			(polygon
				(pts
					(xy 377.313444 -10.281158) (xy 377.821444 -10.281158) (xy 377.821444 -10.662158) (xy 377.313444 -10.662158)
				)
			)
		)
	)
)
